(kicad_pcb
	(version 20241229)
	(generator "pcbnew")
	(generator_version "9.0")
	(general
		(thickness 1.711)
		(legacy_teardrops no)
	)
	(paper "A4")
	(title_block
		(title "Antmicro Baseboard for Jetson AGX Thor")
		(date "2026-02-18")
		(rev "1.1.0")
		(company "Antmicro Ltd")
		(comment 1 "www.antmicro.com")
		(comment 9 "footprints 757-761 of 1170")
	)
	(layers
		(0 "F.Cu" signal)
		(4 "In1.Cu" signal)
		(6 "In2.Cu" signal)
		(8 "In3.Cu" signal)
		(10 "In4.Cu" jumper)
		(12 "In5.Cu" signal)
		(14 "In6.Cu" signal)
		(16 "In7.Cu" signal)
		(18 "In8.Cu" signal)
		(2 "B.Cu" signal)
		(9 "F.Adhes" user "F.Adhesive")
		(11 "B.Adhes" user "B.Adhesive")
		(13 "F.Paste" user)
		(15 "B.Paste" user)
		(5 "F.SilkS" user "F.Silkscreen")
		(7 "B.SilkS" user "B.Silkscreen")
		(1 "F.Mask" user)
		(3 "B.Mask" user)
		(17 "Dwgs.User" user "User.Drawings")
		(19 "Cmts.User" user "User.Comments")
		(21 "Eco1.User" user "User.Eco1")
		(23 "Eco2.User" user "User.Eco2")
		(25 "Edge.Cuts" user)
		(27 "Margin" user)
		(31 "F.CrtYd" user "F.Courtyard")
		(29 "B.CrtYd" user "B.Courtyard")
		(35 "F.Fab" user)
		(33 "B.Fab" user)
	)
	(footprint "antmicro-footprints:TP_SMD_0.75mm"
		(layer "B.Cu")
		(at 197.5 124.3)
		(property "Reference" "TP1"
			(at -0.5 0.9 180)
			(layer "B.SilkS")
			(effects
				(font
					(size 0.7 0.7)
					(thickness 0.15)
				)
				(justify left bottom mirror)
			)
		)
		(property "Value" "TP_0.75mm_SMD"
			(at 0 -1.2 180)
			(layer "B.Fab")
			(effects
				(font
					(size 0.7 0.7)
					(thickness 0.15)
				)
				(justify left bottom mirror)
			)
		)
		(property "Description" "SMT test point"
			(at 0 0 180)
			(layer "B.Fab")
			(hide yes)
			(effects
				(font
					(size 1.27 1.27)
					(thickness 0.15)
				)
				(justify mirror)
			)
		)
		(property "MPN" ""
			(at 0 0 180)
			(unlocked yes)
			(layer "B.Fab")
			(hide yes)
			(effects
				(font
					(size 1 1)
					(thickness 0.15)
				)
				(justify mirror)
			)
		)
		(property "Manufacturer" ""
			(at 0 0 180)
			(unlocked yes)
			(layer "B.Fab")
			(hide yes)
			(effects
				(font
					(size 1 1)
					(thickness 0.15)
				)
				(justify mirror)
			)
		)
		(property "Author" "Antmicro"
			(at 0 0 180)
			(unlocked yes)
			(layer "B.Fab")
			(hide yes)
			(effects
				(font
					(size 1 1)
					(thickness 0.15)
				)
				(justify mirror)
			)
		)
		(property "License" "Apache-2.0"
			(at 0 0 180)
			(unlocked yes)
			(layer "B.Fab")
			(hide yes)
			(effects
				(font
					(size 1 1)
					(thickness 0.15)
				)
				(justify mirror)
			)
		)
		(sheetname "/USB Hub/")
		(sheetfile "usb_hub.kicad_sch")
		(attr exclude_from_pos_files exclude_from_bom)
		(fp_circle
			(center 0 0)
			(end 0.475 0)
			(stroke
				(width 0.05)
				(type default)
			)
			(fill no)
			(layer "B.CrtYd")
		)
		(fp_text user "License: Apache-2.0"
			(at -0.4 -5.101 180)
			(layer "B.Fab")
			(effects
				(font
					(size 0.7 0.7)
					(thickness 0.15)
				)
				(justify left bottom mirror)
			)
		)
		(fp_text user "Author: Antmicro"
			(at -0.4 -3.901 180)
			(layer "B.Fab")
			(effects
				(font
					(size 0.7 0.7)
					(thickness 0.15)
				)
				(justify left bottom mirror)
			)
		)
		(fp_text user "${REFERENCE}"
			(at -0.4 -2.7 180)
			(layer "B.Fab")
			(effects
				(font
					(size 0.7 0.7)
					(thickness 0.15)
				)
				(justify left bottom mirror)
			)
		)
		(pad "1" smd circle
			(at 0 0)
			(size 0.75 0.75)
			(layers "B.Cu" "B.Mask")
			(net 914 "/USB Hub/PRT_CTL1")
			(pinfunction "1")
			(pintype "passive")
		)
	)
	(footprint "antmicro-footprints:R_0402_1005Metric"
		(layer "B.Cu")
		(at 201.3 130.5 90)
		(descr "Resistor SMD 0402")
		(tags "resistor SMD 0402")
		(property "Reference" "R58"
			(at -3.1 -0.3 90)
			(layer "B.SilkS")
			(effects
				(font
					(size 0.7 0.7)
					(thickness 0.15)
				)
				(justify right top mirror)
			)
		)
		(property "Value" "R_0R_0402"
			(at -1.011843 -1.772047 90)
			(layer "B.Fab")
			(effects
				(font
					(size 0.7 0.7)
					(thickness 0.15)
				)
				(justify right top mirror)
			)
		)
		(property "Datasheet" "https://industrial.panasonic.com/cdbs/www-data/pdf/RDA0000/AOA0000C301.pdf"
			(at 0 0 90)
			(layer "B.Fab")
			(hide yes)
			(effects
				(font
					(size 1.27 1.27)
					(thickness 0.15)
				)
				(justify mirror)
			)
		)
		(property "Description" "SMD Chip Resistor, Jumper, 0 ohm, 100 mW, 0402 [1005 Metric], Thick Film, General Purpose"
			(at 0 0 90)
			(layer "B.Fab")
			(hide yes)
			(effects
				(font
					(size 1.27 1.27)
					(thickness 0.15)
				)
				(justify mirror)
			)
		)
		(property "Manufacturer" "Panasonic"
			(at 0 0 270)
			(unlocked yes)
			(layer "B.Fab")
			(hide yes)
			(effects
				(font
					(size 1 1)
					(thickness 0.15)
				)
				(justify mirror)
			)
		)
		(property "MPN" "ERJ2GE0R00X"
			(at 0 0 270)
			(unlocked yes)
			(layer "B.Fab")
			(hide yes)
			(effects
				(font
					(size 1 1)
					(thickness 0.15)
				)
				(justify mirror)
			)
		)
		(property "Val" "0R"
			(at 0 0 270)
			(unlocked yes)
			(layer "B.Fab")
			(hide yes)
			(effects
				(font
					(size 1 1)
					(thickness 0.15)
				)
				(justify mirror)
			)
		)
		(property "License" "Apache-2.0"
			(at 0 0 270)
			(unlocked yes)
			(layer "B.Fab")
			(hide yes)
			(effects
				(font
					(size 1 1)
					(thickness 0.15)
				)
				(justify mirror)
			)
		)
		(property "Author" "Antmicro"
			(at 0 0 270)
			(unlocked yes)
			(layer "B.Fab")
			(hide yes)
			(effects
				(font
					(size 1 1)
					(thickness 0.15)
				)
				(justify mirror)
			)
		)
		(property "Tolerance" "~"
			(at 0 0 270)
			(unlocked yes)
			(layer "B.Fab")
			(hide yes)
			(effects
				(font
					(size 1 1)
					(thickness 0.15)
				)
				(justify mirror)
			)
		)
		(property "Current" "1A"
			(at 0 0 270)
			(unlocked yes)
			(layer "B.Fab")
			(hide yes)
			(effects
				(font
					(size 1 1)
					(thickness 0.15)
				)
				(justify mirror)
			)
		)
		(sheetname "/USB Hub/")
		(sheetfile "usb_hub.kicad_sch")
		(attr smd)
		(fp_rect
			(start -0.925 0.47)
			(end 0.925 -0.47)
			(stroke
				(width 0.05)
				(type default)
			)
			(fill no)
			(layer "B.CrtYd")
		)
		(fp_rect
			(start -0.5 0.25)
			(end 0.5 -0.25)
			(stroke
				(width 0.15)
				(type solid)
			)
			(fill no)
			(layer "B.Fab")
		)
		(fp_text user "${REFERENCE}"
			(at -0.95 -3.168 90)
			(layer "B.Fab")
			(effects
				(font
					(size 0.7 0.7)
					(thickness 0.15)
				)
				(justify right top mirror)
			)
		)
		(fp_text user "Author: Antmicro"
			(at -0.95 -4.169 90)
			(layer "B.Fab")
			(effects
				(font
					(size 0.7 0.7)
					(thickness 0.15)
				)
				(justify right top mirror)
			)
		)
		(fp_text user "License: Apache-2.0"
			(at -0.95 -5.169 90)
			(layer "B.Fab")
			(effects
				(font
					(size 0.7 0.7)
					(thickness 0.15)
				)
				(justify right top mirror)
			)
		)
		(pad "1" smd roundrect
			(at -0.48 0 90)
			(size 0.59 0.64)
			(layers "B.Cu" "B.Mask" "B.Paste")
			(roundrect_rratio 0.25)
			(net 1142 "Net-(U21-USB3DN_RXDP3)")
			(pintype "passive")
		)
		(pad "2" smd roundrect
			(at 0.48 0 90)
			(size 0.59 0.64)
			(layers "B.Cu" "B.Mask" "B.Paste")
			(roundrect_rratio 0.25)
			(net 1 "GND")
			(pintype "passive")
		)
	)
	(footprint "antmicro-footprints:C_0805_2012Metric"
		(layer "B.Cu")
		(at 99.1 126.5 -90)
		(descr "Capacitor SMD 0805")
		(tags "capacitor SMD 0805")
		(property "Reference" "C229"
			(at -1.5 -2.1 90)
			(layer "B.SilkS")
			(effects
				(font
					(size 0.7 0.7)
					(thickness 0.15)
				)
				(justify left bottom mirror)
			)
		)
		(property "Value" "C_22u_25V_0805"
			(at -2.055717 -1.963153 90)
			(layer "B.Fab")
			(effects
				(font
					(size 0.7 0.7)
					(thickness 0.15)
				)
				(justify left bottom mirror)
			)
		)
		(property "Datasheet" "https://product.samsungsem.com/mlcc/CL21A226MAYNNN.do"
			(at 0 0 90)
			(layer "B.Fab")
			(hide yes)
			(effects
				(font
					(size 1.27 1.27)
					(thickness 0.15)
				)
				(justify mirror)
			)
		)
		(property "Description" "SMT Multilayer Ceramic Capacitor, 22uF, +/-20%, 25V, X5R, 0805 [2012 Metric]"
			(at 0 0 90)
			(layer "B.Fab")
			(hide yes)
			(effects
				(font
					(size 1.27 1.27)
					(thickness 0.15)
				)
				(justify mirror)
			)
		)
		(property "MPN" "CL21A226MAYNNNE"
			(at 0 0 270)
			(unlocked yes)
			(layer "B.Fab")
			(hide yes)
			(effects
				(font
					(size 1 1)
					(thickness 0.15)
				)
				(justify mirror)
			)
		)
		(property "Val" "22u"
			(at 0 0 270)
			(unlocked yes)
			(layer "B.Fab")
			(hide yes)
			(effects
				(font
					(size 1 1)
					(thickness 0.15)
				)
				(justify mirror)
			)
		)
		(property "Voltage" "25V"
			(at 0 0 270)
			(unlocked yes)
			(layer "B.Fab")
			(hide yes)
			(effects
				(font
					(size 1 1)
					(thickness 0.15)
				)
				(justify mirror)
			)
		)
		(property "Dielectric" "X5R"
			(at 0 0 270)
			(unlocked yes)
			(layer "B.Fab")
			(hide yes)
			(effects
				(font
					(size 1 1)
					(thickness 0.15)
				)
				(justify mirror)
			)
		)
		(property "Manufacturer" "Samsung Electro-Mechanics"
			(at 0 0 270)
			(unlocked yes)
			(layer "B.Fab")
			(hide yes)
			(effects
				(font
					(size 1 1)
					(thickness 0.15)
				)
				(justify mirror)
			)
		)
		(property "License" "Apache-2.0"
			(at 0 0 270)
			(unlocked yes)
			(layer "B.Fab")
			(hide yes)
			(effects
				(font
					(size 1 1)
					(thickness 0.15)
				)
				(justify mirror)
			)
		)
		(property "Author" "Antmicro"
			(at 0 0 270)
			(unlocked yes)
			(layer "B.Fab")
			(hide yes)
			(effects
				(font
					(size 1 1)
					(thickness 0.15)
				)
				(justify mirror)
			)
		)
		(property "Public" "False"
			(at 0 0 270)
			(unlocked yes)
			(layer "B.Fab")
			(hide yes)
			(effects
				(font
					(size 1 1)
					(thickness 0.15)
				)
				(justify mirror)
			)
		)
		(sheetname "/Expansion connector/")
		(sheetfile "expansion_connector.kicad_sch")
		(attr smd)
		(fp_line
			(start -0.3 0.7)
			(end 0.3 0.7)
			(stroke
				(width 0.15)
				(type solid)
			)
			(layer "B.SilkS")
		)
		(fp_line
			(start -0.3 -0.7)
			(end 0.3 -0.7)
			(stroke
				(width 0.15)
				(type solid)
			)
			(layer "B.SilkS")
		)
		(fp_poly
			(pts
				(xy 1.95 0.9) (xy -1.95 0.9) (xy -1.95 -0.9) (xy 1.95 -0.9)
			)
			(stroke
				(width 0.05)
				(type default)
			)
			(fill no)
			(layer "B.CrtYd")
		)
		(fp_poly
			(pts
				(xy -0.95 0.675001) (xy 0.95 0.675001) (xy 0.95 -0.675001) (xy -0.95 -0.675001)
			)
			(stroke
				(width 0.15)
				(type solid)
			)
			(fill no)
			(layer "B.Fab")
		)
		(fp_text user "Author: Antmicro"
			(at -1.9 -5.947 90)
			(layer "B.Fab")
			(effects
				(font
					(size 0.7 0.7)
					(thickness 0.15)
				)
				(justify left bottom mirror)
			)
		)
		(fp_text user "${REFERENCE}"
			(at -1.899999 -3.947 90)
			(layer "B.Fab")
			(effects
				(font
					(size 0.7 0.7)
					(thickness 0.15)
				)
				(justify left bottom mirror)
			)
		)
		(fp_text user "License: Apache-2.0"
			(at -1.9 -4.947 90)
			(layer "B.Fab")
			(effects
				(font
					(size 0.7 0.7)
					(thickness 0.15)
				)
				(justify left bottom mirror)
			)
		)
		(pad "1" smd roundrect
			(at -1.099999 0 270)
			(size 1.2 1.3)
			(layers "B.Cu" "B.Mask" "B.Paste")
			(roundrect_rratio 0.25)
			(net 1 "GND")
			(pintype "passive")
		)
		(pad "2" smd roundrect
			(at 1.099999 0 270)
			(size 1.2 1.3)
			(layers "B.Cu" "B.Mask" "B.Paste")
			(roundrect_rratio 0.25)
			(net 297 "/Expansion connector/+3V3_FMC")
			(pintype "passive")
		)
	)
	(footprint "antmicro-footprints:TP_SMD_0.75mm"
		(layer "B.Cu")
		(at 137.95 84.1 90)
		(property "Reference" "TP59"
			(at -3.13 -0.31 90)
			(layer "B.SilkS")
			(effects
				(font
					(size 0.7 0.7)
					(thickness 0.15)
				)
				(justify right top mirror)
			)
		)
		(property "Value" "TP_0.75mm_SMD"
			(at 0 -1.2 90)
			(layer "B.Fab")
			(effects
				(font
					(size 0.7 0.7)
					(thickness 0.15)
				)
				(justify right top mirror)
			)
		)
		(property "Description" "SMT test point"
			(at 0 0 90)
			(layer "B.Fab")
			(hide yes)
			(effects
				(font
					(size 1.27 1.27)
					(thickness 0.15)
				)
				(justify mirror)
			)
		)
		(property "MPN" ""
			(at 0 0 270)
			(unlocked yes)
			(layer "B.Fab")
			(hide yes)
			(effects
				(font
					(size 1 1)
					(thickness 0.15)
				)
				(justify mirror)
			)
		)
		(property "Manufacturer" ""
			(at 0 0 270)
			(unlocked yes)
			(layer "B.Fab")
			(hide yes)
			(effects
				(font
					(size 1 1)
					(thickness 0.15)
				)
				(justify mirror)
			)
		)
		(property "Author" "Antmicro"
			(at 0 0 270)
			(unlocked yes)
			(layer "B.Fab")
			(hide yes)
			(effects
				(font
					(size 1 1)
					(thickness 0.15)
				)
				(justify mirror)
			)
		)
		(property "License" "Apache-2.0"
			(at 0 0 270)
			(unlocked yes)
			(layer "B.Fab")
			(hide yes)
			(effects
				(font
					(size 1 1)
					(thickness 0.15)
				)
				(justify mirror)
			)
		)
		(sheetname "/SoM_Power/")
		(sheetfile "som_power.kicad_sch")
		(attr exclude_from_pos_files exclude_from_bom)
		(fp_circle
			(center 0 0)
			(end 0.475 0)
			(stroke
				(width 0.05)
				(type default)
			)
			(fill no)
			(layer "B.CrtYd")
		)
		(fp_text user "License: Apache-2.0"
			(at -0.4 -5.101 90)
			(layer "B.Fab")
			(effects
				(font
					(size 0.7 0.7)
					(thickness 0.15)
				)
				(justify right top mirror)
			)
		)
		(fp_text user "${REFERENCE}"
			(at -0.4 -2.7 90)
			(layer "B.Fab")
			(effects
				(font
					(size 0.7 0.7)
					(thickness 0.15)
				)
				(justify right top mirror)
			)
		)
		(fp_text user "Author: Antmicro"
			(at -0.4 -3.901 90)
			(layer "B.Fab")
			(effects
				(font
					(size 0.7 0.7)
					(thickness 0.15)
				)
				(justify right top mirror)
			)
		)
		(pad "1" smd circle
			(at 0 0 90)
			(size 0.75 0.75)
			(layers "B.Cu" "B.Mask")
			(net 704 "Net-(J1A-GPIO30)")
			(pinfunction "1")
			(pintype "passive")
		)
	)
	(footprint "antmicro-footprints:TSOT23-6"
		(layer "B.Cu")
		(at 210.5 62.5 180)
		(property "Reference" "U47"
			(at -2.1 -1.6 90)
			(layer "B.SilkS")
			(effects
				(font
					(size 0.7 0.7)
					(thickness 0.15)
				)
				(justify right top mirror)
			)
		)
		(property "Value" "AP22615A_TSOT26"
			(at 0 -2.600001 0)
			(layer "B.Fab")
			(effects
				(font
					(size 0.7 0.7)
					(thickness 0.15)
				)
				(justify left bottom mirror)
			)
		)
		(property "Datasheet" "https://www.mouser.com/datasheet/2/115/DIOD_S_A0008958405_1-2543193.pdf"
			(at 0 0 0)
			(layer "B.Fab")
			(hide yes)
			(effects
				(font
					(size 1.27 1.27)
					(thickness 0.15)
				)
				(justify mirror)
			)
		)
		(property "Description" "Power Load Distribution Switch, High Side, Active High, 1 Output, 5.5 V, 3.6 A, 0.04 ohm, TSOT-26-6"
			(at 0 0 0)
			(layer "B.Fab")
			(hide yes)
			(effects
				(font
					(size 1.27 1.27)
					(thickness 0.15)
				)
				(justify mirror)
			)
		)
		(property "MPN" "AP22615AWU-7"
			(at 0 0 0)
			(unlocked yes)
			(layer "B.Fab")
			(hide yes)
			(effects
				(font
					(size 1 1)
					(thickness 0.15)
				)
				(justify mirror)
			)
		)
		(property "Manufacturer" "Diodes Incorporated"
			(at 0 0 0)
			(unlocked yes)
			(layer "B.Fab")
			(hide yes)
			(effects
				(font
					(size 1 1)
					(thickness 0.15)
				)
				(justify mirror)
			)
		)
		(property "Author" "Antmicro"
			(at 0 0 0)
			(unlocked yes)
			(layer "B.Fab")
			(hide yes)
			(effects
				(font
					(size 1 1)
					(thickness 0.15)
				)
				(justify mirror)
			)
		)
		(property "License" "Apache-2.0"
			(at 0 0 0)
			(unlocked yes)
			(layer "B.Fab")
			(hide yes)
			(effects
				(font
					(size 1 1)
					(thickness 0.15)
				)
				(justify mirror)
			)
		)
		(sheetname "/CSI/")
		(sheetfile "csi.kicad_sch")
		(attr smd)
		(fp_line
			(start 1 1.497)
			(end 1 1.375)
			(stroke
				(width 0.15)
				(type solid)
			)
			(layer "B.SilkS")
		)
		(fp_line
			(start 1 1.497)
			(end -1 1.5)
			(stroke
				(width 0.15)
				(type solid)
			)
			(layer "B.SilkS")
		)
		(fp_line
			(start 1 -1.55)
			(end 1 -1.4)
			(stroke
				(width 0.15)
				(type solid)
			)
			(layer "B.SilkS")
		)
		(fp_line
			(start 1 -1.55)
			(end -1 -1.55)
			(stroke
				(width 0.15)
				(type solid)
			)
			(layer "B.SilkS")
		)
		(fp_line
			(start -1 1.5)
			(end -1 1.375)
			(stroke
				(width 0.15)
				(type solid)
			)
			(layer "B.SilkS")
		)
		(fp_line
			(start -1 -1.55)
			(end -1 -1.4)
			(stroke
				(width 0.15)
				(type solid)
			)
			(layer "B.SilkS")
		)
		(fp_circle
			(center -1.44 1.5)
			(end -1.39 1.5)
			(stroke
				(width 0.15)
				(type solid)
			)
			(fill yes)
			(layer "B.SilkS")
		)
		(fp_poly
			(pts
				(xy 1.930001 1.7) (xy 1.930001 -1.7) (xy -1.930001 -1.7) (xy -1.930001 1.7)
			)
			(stroke
				(width 0.05)
				(type solid)
			)
			(fill no)
			(layer "B.CrtYd")
		)
		(fp_line
			(start -0.45 1.520999)
			(end -0.876001 1.096)
			(stroke
				(width 0.15)
				(type solid)
			)
			(layer "B.Fab")
		)
		(fp_poly
			(pts
				(xy 0.875 -1.528) (xy 0.875 1.525) (xy -0.875 1.525) (xy -0.875 -1.528)
			)
			(stroke
				(width 0.15)
				(type solid)
			)
			(fill no)
			(layer "B.Fab")
		)
		(fp_text user "License: Apache-2.0"
			(at -1.93 -6.199 0)
			(layer "B.Fab")
			(effects
				(font
					(size 0.7 0.7)
					(thickness 0.15)
				)
				(justify left bottom mirror)
			)
		)
		(fp_text user "${REFERENCE}"
			(at -1.93 -3.8 0)
			(layer "B.Fab")
			(effects
				(font
					(size 0.7 0.7)
					(thickness 0.15)
				)
				(justify left bottom mirror)
			)
		)
		(fp_text user "Author: Antmicro"
			(at -1.93 -5 0)
			(layer "B.Fab")
			(effects
				(font
					(size 0.7 0.7)
					(thickness 0.15)
				)
				(justify left bottom mirror)
			)
		)
		(pad "1" smd rect
			(at -1.301 0.947 270)
			(size 0.7 1.2)
			(layers "B.Cu" "B.Mask" "B.Paste")
			(net 8 "/CSI/CSIB_3V3")
			(pinfunction "OUT")
			(pintype "power_out")
		)
		(pad "2" smd rect
			(at -1.300999 -0.004 270)
			(size 0.7 1.2)
			(layers "B.Cu" "B.Mask" "B.Paste")
			(net 1 "GND")
			(pinfunction "GND")
			(pintype "power_in")
		)
		(pad "3" smd rect
			(at -1.301 -0.954 270)
			(size 0.7 1.2)
			(layers "B.Cu" "B.Mask" "B.Paste")
			(net 117 "/CSI/CAM_CTRL.CSIB_FLG")
			(pinfunction "FLG")
			(pintype "output")
		)
		(pad "4" smd rect
			(at 1.299 -0.954 270)
			(size 0.7 1.2)
			(layers "B.Cu" "B.Mask" "B.Paste")
			(net 123 "/CSI/CAM_CTRL.CSIB_PEN")
			(pinfunction "EN")
			(pintype "input")
		)
		(pad "5" smd rect
			(at 1.299 -0.004 270)
			(size 0.7 1.2)
			(layers "B.Cu" "B.Mask" "B.Paste")
			(net 998 "/CSI/CSIB_3V3_ISET")
			(pinfunction "ISET")
			(pintype "passive")
		)
		(pad "6" smd rect
			(at 1.299 0.947 270)
			(size 0.7 1.2)
			(layers "B.Cu" "B.Mask" "B.Paste")
			(net 2 "+3V3")
			(pinfunction "IN")
			(pintype "power_in")
		)
	)
)
